# S9S_MB_2U (Grand Teton) — schematic netlist excerpt (pin names and nets, part order shuffled) for the footprints in the layout excerpt that follows; sources: Cadence DE-HDL packaged netlist, KiCad conversion of 03242023_DA0F0TMBIJ0_F0T_Motherboard_J_brd_V01_OCP.brd

PC1206  Q_CAP  22UF 4V 20% X6S  pkg C0805  page 282 : A = PVNN_MAIN_CPU0 ; B = GND
PR702  Q_RES  0 5% CHIP  pkg 0402LF  page 289 : A = P5V ; B = PVCCFA_EHV_FIVRA_CPU1_PVCC2
R4196  Q_RES  1K 1% EMPTY  pkg 0402LF  page 170 : A = P3V3_AUX ; B = U271_1_ADD1

(kicad_pcb
	(version 20260206)
	(generator "pcbnew")
	(generator_version "10.0")
	(general
		(thickness 1.6)
		(legacy_teardrops no)
	)
	(paper "A4")
	(title_block
		(title "03242023_DA0F0TMBIJ0_F0T_Motherboard_J_brd_V01_OCP.brd")
		(comment 1 "Grand Teton / footprints 3550-3552 of 6105")
	)
	(layers
		(0 "F.Cu" signal "TOP")
		(4 "In1.Cu" signal "GND")
		(6 "In2.Cu" signal "IN1")
		(8 "In3.Cu" signal "GND1")
		(10 "In4.Cu" signal "IN2")
		(12 "In5.Cu" signal "GND2")
		(14 "In6.Cu" signal "IN3")
		(16 "In7.Cu" signal "GND3")
		(18 "In8.Cu" signal "VCC")
		(20 "In9.Cu" signal "VCC1")
		(22 "In10.Cu" signal "GND4")
		(24 "In11.Cu" signal "IN4")
		(26 "In12.Cu" signal "GND5")
		(28 "In13.Cu" signal "IN5")
		(30 "In14.Cu" signal "GND6")
		(32 "In15.Cu" signal "IN6")
		(34 "In16.Cu" signal "GND7")
		(2 "B.Cu" signal "BOTTOM")
		(9 "F.Adhes" user "F.Adhesive")
		(11 "B.Adhes" user "B.Adhesive")
		(13 "F.Paste" user "Package Geometry/Pastemask Top")
		(15 "B.Paste" user "Package Geometry/Pastemask Bottom")
		(5 "F.SilkS" user "Ref Des/Silkscreen Top")
		(7 "B.SilkS" user "Ref Des/Silkscreen Bottom")
		(1 "F.Mask" user "Board Geometry/Soldermask Top")
		(3 "B.Mask" user "Board Geometry/Soldermask Bottom")
		(17 "Dwgs.User" user "User.Drawings")
		(19 "Cmts.User" user "User.Comments")
		(21 "Eco1.User" user "User.Eco1")
		(23 "Eco2.User" user "User.Eco2")
		(25 "Edge.Cuts" user "Board Geometry/Outline")
		(27 "Margin" user)
		(31 "F.CrtYd" user "Package Geometry/Place Bound Top")
		(29 "B.CrtYd" user "Package Geometry/Place Bound Bottom")
		(35 "F.Fab" user "Ref Des/Assembly Top")
		(33 "B.Fab" user "Ref Des/Assembly Bottom")
	)
	(footprint ""
		(layer "F.Cu")
		(at 446.780158 -177.78476)
		(property "Reference" "PC1206"
			(at 0 0 0)
			(layer "F.SilkS")
			(hide yes)
			(effects
				(font
					(size 1.27 1.27)
				)
			)
		)
		(property "Value" ""
			(at 0 0 0)
			(layer "F.Fab")
			(effects
				(font
					(size 1.27 1.27)
				)
			)
		)
		(duplicate_pad_numbers_are_jumpers no)
		(fp_line
			(start -1.524 -0.762)
			(end 1.524 -0.762)
			(stroke
				(width 0.1524)
				(type default)
			)
			(layer "F.SilkS")
		)
		(fp_line
			(start -1.524 0.762)
			(end -1.524 -0.762)
			(stroke
				(width 0.1524)
				(type default)
			)
			(layer "F.SilkS")
		)
		(fp_line
			(start 1.524 -0.762)
			(end 1.524 0.762)
			(stroke
				(width 0.1524)
				(type default)
			)
			(layer "F.SilkS")
		)
		(fp_line
			(start 1.524 0.762)
			(end -1.524 0.762)
			(stroke
				(width 0.1524)
				(type default)
			)
			(layer "F.SilkS")
		)
		(fp_line
			(start -1.1049 -0.724916)
			(end -1.1049 0.724916)
			(stroke
				(width 0.1)
				(type default)
			)
			(layer "F.Fab")
		)
		(fp_line
			(start -1.1049 0.724916)
			(end 1.1049 0.724916)
			(stroke
				(width 0.1)
				(type default)
			)
			(layer "F.Fab")
		)
		(fp_line
			(start 1.1049 -0.724916)
			(end -1.1049 -0.724916)
			(stroke
				(width 0.1)
				(type default)
			)
			(layer "F.Fab")
		)
		(fp_line
			(start 1.1049 0.724916)
			(end 1.1049 -0.724916)
			(stroke
				(width 0.1)
				(type default)
			)
			(layer "F.Fab")
		)
		(pad "1" smd rect
			(at -0.889 0 180)
			(size 1.016 1.27)
			(layers "F.Cu" "F.Mask" "F.Paste")
			(net "PVNN_MAIN_CPU0")
		)
		(pad "2" smd rect
			(at 0.889 0 180)
			(size 1.016 1.27)
			(layers "F.Cu" "F.Mask" "F.Paste")
			(net "GND")
		)
	)
	(footprint ""
		(layer "F.Cu")
		(at 297.147234 -15.572994 180)
		(property "Reference" "R4196"
			(at 0 0 180)
			(layer "F.SilkS")
			(hide yes)
			(effects
				(font
					(size 1.27 1.27)
				)
			)
		)
		(property "Value" ""
			(at 0 0 180)
			(layer "F.Fab")
			(effects
				(font
					(size 1.27 1.27)
				)
			)
		)
		(duplicate_pad_numbers_are_jumpers no)
		(fp_line
			(start 0.7874 0.4064)
			(end -0.7874 0.4064)
			(stroke
				(width 0.1524)
				(type default)
			)
			(layer "F.SilkS")
		)
		(fp_line
			(start 0.7874 -0.4064)
			(end 0.7874 0.4064)
			(stroke
				(width 0.1524)
				(type default)
			)
			(layer "F.SilkS")
		)
		(fp_line
			(start -0.7874 0.4064)
			(end -0.7874 -0.4064)
			(stroke
				(width 0.1524)
				(type default)
			)
			(layer "F.SilkS")
		)
		(fp_line
			(start -0.7874 -0.4064)
			(end 0.7874 -0.4064)
			(stroke
				(width 0.1524)
				(type default)
			)
			(layer "F.SilkS")
		)
		(fp_line
			(start 0.67945 0.3048)
			(end 0.120396 0.3048)
			(stroke
				(width 0.1)
				(type default)
			)
			(layer "F.Fab")
		)
		(fp_line
			(start 0.67945 -0.3048)
			(end 0.67945 0.3048)
			(stroke
				(width 0.1)
				(type default)
			)
			(layer "F.Fab")
		)
		(fp_line
			(start 0.12065 -0.2794)
			(end 0.12065 -0.3048)
			(stroke
				(width 0.1)
				(type default)
			)
			(layer "F.Fab")
		)
		(fp_line
			(start 0.12065 -0.3048)
			(end 0.67945 -0.3048)
			(stroke
				(width 0.1)
				(type default)
			)
			(layer "F.Fab")
		)
		(fp_line
			(start 0.120396 0.3048)
			(end 0.120396 0.2794)
			(stroke
				(width 0.1)
				(type default)
			)
			(layer "F.Fab")
		)
		(fp_line
			(start 0.120396 0.2794)
			(end -0.12065 0.2794)
			(stroke
				(width 0.1)
				(type default)
			)
			(layer "F.Fab")
		)
		(fp_line
			(start -0.12065 0.3048)
			(end -0.67945 0.3048)
			(stroke
				(width 0.1)
				(type default)
			)
			(layer "F.Fab")
		)
		(fp_line
			(start -0.12065 0.2794)
			(end -0.12065 0.3048)
			(stroke
				(width 0.1)
				(type default)
			)
			(layer "F.Fab")
		)
		(fp_line
			(start -0.12065 -0.2794)
			(end 0.12065 -0.2794)
			(stroke
				(width 0.1)
				(type default)
			)
			(layer "F.Fab")
		)
		(fp_line
			(start -0.12065 -0.305054)
			(end -0.12065 -0.2794)
			(stroke
				(width 0.1)
				(type default)
			)
			(layer "F.Fab")
		)
		(fp_line
			(start -0.67945 0.3048)
			(end -0.67945 -0.305054)
			(stroke
				(width 0.1)
				(type default)
			)
			(layer "F.Fab")
		)
		(fp_line
			(start -0.67945 -0.305054)
			(end -0.12065 -0.305054)
			(stroke
				(width 0.1)
				(type default)
			)
			(layer "F.Fab")
		)
		(pad "1" smd circle
			(at -0.40005 0 180)
			(size 0 0)
			(layers "F.Cu" "F.Mask" "F.Paste")
			(net "P3V3_AUX")
		)
		(pad "2" smd circle
			(at 0.40005 0 180)
			(size 0 0)
			(layers "F.Cu" "F.Mask" "F.Paste")
			(net "U271_1_ADD1")
		)
	)
	(footprint ""
		(layer "F.Cu")
		(at 36.605718 -354.65385)
		(property "Reference" "PR702"
			(at 0 0 0)
			(layer "F.SilkS")
			(hide yes)
			(effects
				(font
					(size 1.27 1.27)
				)
			)
		)
		(property "Value" ""
			(at 0 0 0)
			(layer "F.Fab")
			(effects
				(font
					(size 1.27 1.27)
				)
			)
		)
		(duplicate_pad_numbers_are_jumpers no)
		(fp_line
			(start -0.7874 -0.4064)
			(end 0.7874 -0.4064)
			(stroke
				(width 0.1524)
				(type default)
			)
			(layer "F.SilkS")
		)
		(fp_line
			(start -0.7874 0.4064)
			(end -0.7874 -0.4064)
			(stroke
				(width 0.1524)
				(type default)
			)
			(layer "F.SilkS")
		)
		(fp_line
			(start 0.7874 -0.4064)
			(end 0.7874 0.4064)
			(stroke
				(width 0.1524)
				(type default)
			)
			(layer "F.SilkS")
		)
		(fp_line
			(start 0.7874 0.4064)
			(end -0.7874 0.4064)
			(stroke
				(width 0.1524)
				(type default)
			)
			(layer "F.SilkS")
		)
		(fp_line
			(start -0.67945 -0.305054)
			(end -0.12065 -0.305054)
			(stroke
				(width 0.1)
				(type default)
			)
			(layer "F.Fab")
		)
		(fp_line
			(start -0.67945 0.3048)
			(end -0.67945 -0.305054)
			(stroke
				(width 0.1)
				(type default)
			)
			(layer "F.Fab")
		)
		(fp_line
			(start -0.12065 -0.305054)
			(end -0.12065 -0.2794)
			(stroke
				(width 0.1)
				(type default)
			)
			(layer "F.Fab")
		)
		(fp_line
			(start -0.12065 -0.2794)
			(end 0.12065 -0.2794)
			(stroke
				(width 0.1)
				(type default)
			)
			(layer "F.Fab")
		)
		(fp_line
			(start -0.12065 0.2794)
			(end -0.12065 0.3048)
			(stroke
				(width 0.1)
				(type default)
			)
			(layer "F.Fab")
		)
		(fp_line
			(start -0.12065 0.3048)
			(end -0.67945 0.3048)
			(stroke
				(width 0.1)
				(type default)
			)
			(layer "F.Fab")
		)
		(fp_line
			(start 0.120396 0.2794)
			(end -0.12065 0.2794)
			(stroke
				(width 0.1)
				(type default)
			)
			(layer "F.Fab")
		)
		(fp_line
			(start 0.120396 0.3048)
			(end 0.120396 0.2794)
			(stroke
				(width 0.1)
				(type default)
			)
			(layer "F.Fab")
		)
		(fp_line
			(start 0.12065 -0.3048)
			(end 0.67945 -0.3048)
			(stroke
				(width 0.1)
				(type default)
			)
			(layer "F.Fab")
		)
		(fp_line
			(start 0.12065 -0.2794)
			(end 0.12065 -0.3048)
			(stroke
				(width 0.1)
				(type default)
			)
			(layer "F.Fab")
		)
		(fp_line
			(start 0.67945 -0.3048)
			(end 0.67945 0.3048)
			(stroke
				(width 0.1)
				(type default)
			)
			(layer "F.Fab")
		)
		(fp_line
			(start 0.67945 0.3048)
			(end 0.120396 0.3048)
			(stroke
				(width 0.1)
				(type default)
			)
			(layer "F.Fab")
		)
		(pad "1" smd circle
			(at -0.40005 0)
			(size 0 0)
			(layers "F.Cu" "F.Mask" "F.Paste")
			(net "P5V")
		)
		(pad "2" smd circle
			(at 0.40005 0)
			(size 0 0)
			(layers "F.Cu" "F.Mask" "F.Paste")
			(net "PVCCFA_EHV_FIVRA_CPU1_PVCC2")
		)
	)
)
